(kicad_pcb
	(version 20260206)
	(generator "pcbnew")
	(generator_version "10.0")
	(general
		(thickness 1.6)
		(legacy_teardrops no)
	)
	(paper "A4")
	(title_block
		(title "Bryce Canyon_SCC_16316-1_OCP.brd")
		(comment 1 "Bryce Canyon / footprint 257 of 1561 (CN6), pads 76-76 of 76")
	)
	(layers
		(0 "F.Cu" signal "TOP")
		(4 "In1.Cu" signal "L2GND")
		(6 "In2.Cu" signal "L3")
		(8 "In3.Cu" signal "L4VCC")
		(10 "In4.Cu" signal "L5VCC")
		(12 "In5.Cu" signal "L6")
		(14 "In6.Cu" signal "L7GND")
		(2 "B.Cu" signal "BOTTOM")
		(9 "F.Adhes" user "F.Adhesive")
		(11 "B.Adhes" user "B.Adhesive")
		(13 "F.Paste" user "Package Geometry/Pastemask Top")
		(15 "B.Paste" user "Package Geometry/Pastemask Bottom")
		(5 "F.SilkS" user "Ref Des/Silkscreen Top")
		(7 "B.SilkS" user "Ref Des/Silkscreen Bottom")
		(1 "F.Mask" user "Board Geometry/Soldermask Top")
		(3 "B.Mask" user "Board Geometry/Soldermask Bottom")
		(17 "Dwgs.User" user "User.Drawings")
		(19 "Cmts.User" user "User.Comments")
		(21 "Eco1.User" user "User.Eco1")
		(23 "Eco2.User" user "User.Eco2")
		(25 "Edge.Cuts" user "Board Geometry/Outline")
		(27 "Margin" user)
		(31 "F.CrtYd" user "Package Geometry/Place Bound Top")
		(29 "B.CrtYd" user "Package Geometry/Place Bound Bottom")
		(35 "F.Fab" user "Ref Des/Assembly Top")
		(33 "B.Fab" user "Ref Des/Assembly Bottom")
	)
	(footprint ""
		(layer "F.Cu")
		(at 179.999894 -3.800094)
		(property "Reference" "CN6"
			(at 0 0 0)
			(layer "F.SilkS")
			(hide yes)
			(effects
				(font
					(size 1.27 1.27)
				)
			)
		)
		(property "Value" "AMP-CONN76-8R-7-GP"
			(at -11.755374 -18.361152 0)
			(unlocked yes)
			(layer "F.Fab")
			(hide yes)
			(effects
				(font
					(size 1.016 1.016)
					(thickness 0.1524)
				)
			)
		)
		(property "Device Type" "PREFIT-76P-144260H400"
			(at -11.755374 -19.885152 0)
			(unlocked yes)
			(layer "F.Fab")
			(hide yes)
			(effects
				(font
					(size 1.016 1.016)
					(thickness 0.1524)
				)
			)
		)
		(duplicate_pad_numbers_are_jumpers no)
		(pad "GND28" thru_hole circle
			(at 12.599924 -8.50011)
			(size 0.762 0.762)
			(drill 0.359918)
			(layers "*.Cu" "*.Mask")
			(remove_unused_layers no)
			(net "GND")
			(clearance 0.1651)
			(thermal_gap 0.1651)
		)
	)
)
